FILE_TYPE = CONNECTIVITY;
{Allegro Design Entry HDL 16.6-p007 (v16-6-112F) 10/10/2012}
"PAGE_NUMBER" = 100;
0"NC";
1"PVDDQ_KLM\g";
2"GND\g";
3"PVDDQ_GHJ\g";
4"PVDDQ_KLM\g";
5"GND\g";
6"GND\g";
7"PVDDQ_GHJ\g";
8"PVDDQ_KLM\g";
9"GND\g";
10"GND\g";
11"PVDDQ_GHJ\g";
12"GND\g";
13"M_K_CPU_VREF";
14"M_G_CPU_VREF";
15"M_K_VREF";
16"M_G_VREF";
17"M_H_CPU_VREF";
18"M_L_CPU_VREF";
19"M_L_VREF";
20"M_H_VREF";
21"M_M_CPU_VREF";
22"M_M_VREF";
23"M_J_CPU_VREF";
24"M_J_VREF";
%"PVDDQ_KLM"
"1","(-1900,2525)","0","mstr_symbols","I10";
;
HDL_POWER"PVDDQ_KLM"
BODY_TYPE"PLUMBING"
CDS_LIB"mstr_symbols"
VOLTAGE"1.2V";
"G\NAC"1;
%"RES"
"2","(-1900,2275)","2","mstr_discrete","I11";
;
CDS_SEC"1"
ROOM"MEM"
CDS_LOCATION"R9M1"
SEC"1"
SEC_TYPE"0402"
CDS_LIB"mstr_discrete"
BOM_COST"SM_CONTROLLER"
WATTAGE"1/16W"
MATERIAL"CHIP"
PACK_TYPE"0402"
TOLERANCE"1%"
VALUE"1.00K"
PART_NUMBER"G21796-026"
LOCATION"R9M1";
"A"
$PN"1"1;
"B"
$PN"2"15;
%"RES"
"1","(-2125,1950)","0","mstr_discrete","I13";
;
CDS_SEC"1"
ROOM"PROC"
CDS_LOCATION"R9M2"
SEC"1"
BOM_COST"PROC_SOCKET"
SEC_TYPE"0402"
CDS_LIB"mstr_discrete"
WATTAGE"1/16W"
MATERIAL"CHIP"
PACK_TYPE"0402"
TOLERANCE"1.0%"
VALUE"2"
PART_NUMBER"G21796-274"
LOCATION"R9M2";
"B"
$PN"2"15;
"A"
$PN"1"13;
%"GND"
"1","(-2125,1300)","0","mstr_symbols","I14";
;
HDL_POWER"GND"
BODY_TYPE"PLUMBING"
CDS_LIB"mstr_symbols"
SIZE"1B"
VOLTAGE"0";
"A\NAC"2;
%"CAP_A"
"1","(-2350,1650)","0","dev_discrete","I15";
;
ROOM"MEM"
SEC"1"
SEC_TYPE"0402V"
CDS_SEC"1"
CDS_LIB"dev_discrete"
BOM_COST"SM_CONTROLLER"
CDS_LOCATION"C9M2"
MATERIAL"X7R"
VOLTAGE"25V"
PACK_TYPE"0402V"
TOLERANCE"10%"
VALUE"0.01UF"
PART_NUMBER"A36096-045"
LOCATION"C9M2";
"B"
$PN"2"2;
"A"
$PN"1"13;
%"PVDDQ_GHJ"
"1","(450,4200)","0","mstr_symbols","I17";
;
HDL_POWER"PVDDQ_GHJ"
BODY_TYPE"PLUMBING"
CDS_LIB"mstr_symbols"
VOLTAGE"1.2V";
"G\NAC"3;
%"RES"
"2","(450,3950)","2","mstr_discrete","I19";
;
CDS_SEC"1"
ROOM"MEM"
CDS_LOCATION"R1G2"
SEC"1"
CDS_LIB"mstr_discrete"
BOM_COST"SM_CONTROLLER"
SEC_TYPE"0402"
WATTAGE"1/16W"
MATERIAL"CHIP"
PACK_TYPE"0402"
TOLERANCE"1%"
VALUE"1.00K"
PART_NUMBER"G21796-026"
LOCATION"R1G2";
"A"
$PN"1"3;
"B"
$PN"2"20;
%"RES"
"2","(-1825,3300)","2","mstr_discrete","I2";
;
CDS_SEC"1"
ROOM"MEM"
CDS_LOCATION"R1F6"
SEC"1"
SEC_TYPE"0402"
BOM_COST"SM_CONTROLLER"
CDS_LIB"mstr_discrete"
WATTAGE"1/16W"
MATERIAL"CHIP"
PACK_TYPE"0402"
TOLERANCE"1%"
VALUE"1.00K"
PART_NUMBER"G21796-026"
LOCATION"R1F6";
"A"
$PN"1"16;
"B"
$PN"2"12;
%"RES"
"2","(525,3300)","2","mstr_discrete","I20";
;
CDS_SEC"1"
ROOM"MEM"
CDS_LOCATION"R1G3"
SEC"1"
CDS_LIB"mstr_discrete"
BOM_COST"SM_CONTROLLER"
SEC_TYPE"0402"
WATTAGE"1/16W"
MATERIAL"CHIP"
PACK_TYPE"0402"
TOLERANCE"1%"
VALUE"1.00K"
PART_NUMBER"G21796-026"
LOCATION"R1G3";
"A"
$PN"1"20;
"B"
$PN"2"5;
%"PVDDQ_KLM"
"1","(450,2525)","0","mstr_symbols","I21";
;
HDL_POWER"PVDDQ_KLM"
BODY_TYPE"PLUMBING"
CDS_LIB"mstr_symbols"
VOLTAGE"1.2V";
"G\NAC"4;
%"RES"
"2","(450,2275)","2","mstr_discrete","I22";
;
CDS_SEC"1"
ROOM"MEM"
CDS_LOCATION"R9L7"
SEC"1"
BOM_COST"SM_CONTROLLER"
CDS_LIB"mstr_discrete"
SEC_TYPE"0402"
WATTAGE"1/16W"
MATERIAL"CHIP"
PACK_TYPE"0402"
TOLERANCE"1%"
VALUE"1.00K"
PART_NUMBER"G21796-026"
LOCATION"R9L7";
"A"
$PN"1"4;
"B"
$PN"2"19;
%"RES"
"2","(525,1625)","2","mstr_discrete","I24";
;
CDS_SEC"1"
ROOM"PROC"
CDS_LOCATION"R9L6"
SEC"1"
CDS_LIB"mstr_discrete"
BOM_COST"PROC_SOCKET"
SEC_TYPE"0402"
WATTAGE"1/16W"
MATERIAL"CHIP"
PACK_TYPE"0402"
TOLERANCE"1%"
VALUE"1.00K"
PART_NUMBER"G21796-026"
LOCATION"R9L6";
"A"
$PN"1"19;
"B"
$PN"2"6;
%"RES"
"1","(225,3625)","0","mstr_discrete","I25";
;
CDS_SEC"1"
ROOM"PROC"
CDS_LOCATION"R1G1"
SEC"1"
BOM_COST"PROC_SOCKET"
CDS_LIB"mstr_discrete"
SEC_TYPE"0402"
WATTAGE"1/16W"
MATERIAL"CHIP"
PACK_TYPE"0402"
TOLERANCE"1.0%"
VALUE"2"
PART_NUMBER"G21796-274"
LOCATION"R1G1";
"B"
$PN"2"20;
"A"
$PN"1"17;
%"CAP_A"
"1","(0,3325)","0","dev_discrete","I26";
;
ROOM"PROC"
SEC"1"
SEC_TYPE"0402V"
CDS_SEC"1"
CDS_LIB"dev_discrete"
BOM_COST"PROC_SOCKET"
CDS_LOCATION"C1G8"
MATERIAL"X7R"
VOLTAGE"25V"
PACK_TYPE"0402V"
TOLERANCE"10%"
VALUE"0.01UF"
PART_NUMBER"A36096-045"
LOCATION"C1G8";
"B"
$PN"2"5;
"A"
$PN"1"17;
%"GND"
"1","(225,2975)","0","mstr_symbols","I28";
;
HDL_POWER"GND"
BODY_TYPE"PLUMBING"
SIZE"1B"
CDS_LIB"mstr_symbols"
VOLTAGE"0";
"A\NAC"5;
%"RES"
"1","(225,1950)","0","mstr_discrete","I29";
;
CDS_SEC"1"
ROOM"PROC"
CDS_LOCATION"R9L8"
SEC"1"
CDS_LIB"mstr_discrete"
SEC_TYPE"0402"
BOM_COST"PROC_SOCKET"
WATTAGE"1/16W"
MATERIAL"CHIP"
PACK_TYPE"0402"
TOLERANCE"1.0%"
VALUE"2"
PART_NUMBER"G21796-274"
LOCATION"R9L8";
"B"
$PN"2"19;
"A"
$PN"1"18;
%"CAP_A"
"1","(0,1650)","0","dev_discrete","I30";
;
ROOM"MEM"
SEC"1"
SEC_TYPE"0402V"
CDS_SEC"1"
CDS_LIB"dev_discrete"
BOM_COST"SM_CONTROLLER"
CDS_LOCATION"C9L8"
MATERIAL"X7R"
VOLTAGE"25V"
PACK_TYPE"0402V"
TOLERANCE"10%"
VALUE"0.01UF"
PART_NUMBER"A36096-045"
LOCATION"C9L8";
"B"
$PN"2"6;
"A"
$PN"1"18;
%"GND"
"1","(225,1300)","0","mstr_symbols","I31";
;
HDL_POWER"GND"
BODY_TYPE"PLUMBING"
SIZE"1B"
CDS_LIB"mstr_symbols"
VOLTAGE"0";
"A\NAC"6;
%"PVDDQ_GHJ"
"1","(2900,4200)","0","mstr_symbols","I33";
;
HDL_POWER"PVDDQ_GHJ"
BODY_TYPE"PLUMBING"
CDS_LIB"mstr_symbols"
VOLTAGE"1.2V";
"G\NAC"7;
%"RES"
"2","(2900,3950)","2","mstr_discrete","I35";
;
CDS_SEC"1"
ROOM"MEM"
CDS_LOCATION"R1G15"
SEC"1"
CDS_LIB"mstr_discrete"
BOM_COST"SM_CONTROLLER"
SEC_TYPE"0402"
WATTAGE"1/16W"
MATERIAL"CHIP"
PACK_TYPE"0402"
TOLERANCE"1%"
VALUE"1.00K"
PART_NUMBER"G21796-026"
LOCATION"R1G15";
"A"
$PN"1"7;
"B"
$PN"2"24;
%"RES"
"2","(2975,3300)","2","mstr_discrete","I36";
;
CDS_SEC"1"
ROOM"MEM"
CDS_LOCATION"R1G17"
SEC"1"
CDS_LIB"mstr_discrete"
BOM_COST"SM_CONTROLLER"
SEC_TYPE"0402"
WATTAGE"1/16W"
MATERIAL"CHIP"
PACK_TYPE"0402"
TOLERANCE"1%"
VALUE"1.00K"
PART_NUMBER"G21796-026"
LOCATION"R1G17";
"A"
$PN"1"24;
"B"
$PN"2"9;
%"PVDDQ_KLM"
"1","(2900,2525)","0","mstr_symbols","I37";
;
HDL_POWER"PVDDQ_KLM"
BODY_TYPE"PLUMBING"
CDS_LIB"mstr_symbols"
VOLTAGE"1.2V";
"G\NAC"8;
%"RES"
"2","(2900,2275)","2","mstr_discrete","I38";
;
CDS_SEC"1"
ROOM"MEM"
CDS_LOCATION"R9L2"
SEC"1"
BOM_COST"SM_CONTROLLER"
CDS_LIB"mstr_discrete"
SEC_TYPE"0402"
WATTAGE"1/16W"
MATERIAL"CHIP"
PACK_TYPE"0402"
TOLERANCE"1%"
VALUE"1.00K"
PART_NUMBER"G21796-026"
LOCATION"R9L2";
"A"
$PN"1"8;
"B"
$PN"2"22;
%"RES"
"2","(-1825,1625)","2","mstr_discrete","I4";
;
CDS_SEC"1"
ROOM"PROC"
CDS_LOCATION"R9L11"
SEC"1"
SEC_TYPE"0402"
BOM_COST"PROC_SOCKET"
CDS_LIB"mstr_discrete"
WATTAGE"1/16W"
MATERIAL"CHIP"
PACK_TYPE"0402"
TOLERANCE"1%"
VALUE"1.00K"
PART_NUMBER"G21796-026"
LOCATION"R9L11";
"A"
$PN"1"15;
"B"
$PN"2"2;
%"RES"
"2","(2975,1625)","2","mstr_discrete","I40";
;
CDS_SEC"1"
ROOM"PROC"
CDS_LOCATION"R9L1"
SEC"1"
CDS_LIB"mstr_discrete"
BOM_COST"PROC_SOCKET"
SEC_TYPE"0402"
WATTAGE"1/16W"
MATERIAL"CHIP"
PACK_TYPE"0402"
TOLERANCE"1%"
VALUE"1.00K"
PART_NUMBER"G21796-026"
LOCATION"R9L1";
"A"
$PN"1"22;
"B"
$PN"2"10;
%"RES"
"1","(2675,3625)","0","mstr_discrete","I41";
;
CDS_SEC"1"
ROOM"PROC"
CDS_LOCATION"R1G14"
SEC"1"
BOM_COST"PROC_SOCKET"
CDS_LIB"mstr_discrete"
SEC_TYPE"0402"
WATTAGE"1/16W"
MATERIAL"CHIP"
PACK_TYPE"0402"
TOLERANCE"1.0%"
VALUE"2"
PART_NUMBER"G21796-274"
LOCATION"R1G14";
"B"
$PN"2"24;
"A"
$PN"1"23;
%"CAP_A"
"1","(2450,3325)","0","dev_discrete","I42";
;
ROOM"PROC"
SEC"1"
SEC_TYPE"0402V"
CDS_SEC"1"
CDS_LIB"dev_discrete"
BOM_COST"PROC_SOCKET"
CDS_LOCATION"C1G18"
MATERIAL"X7R"
VOLTAGE"25V"
PACK_TYPE"0402V"
TOLERANCE"10%"
VALUE"0.01UF"
PART_NUMBER"A36096-045"
LOCATION"C1G18";
"B"
$PN"2"9;
"A"
$PN"1"23;
%"GND"
"1","(2675,2975)","0","mstr_symbols","I44";
;
HDL_POWER"GND"
BODY_TYPE"PLUMBING"
SIZE"1B"
CDS_LIB"mstr_symbols"
VOLTAGE"0";
"A\NAC"9;
%"RES"
"1","(2675,1950)","0","mstr_discrete","I45";
;
CDS_SEC"1"
ROOM"PROC"
CDS_LOCATION"R9L3"
SEC"1"
CDS_LIB"mstr_discrete"
SEC_TYPE"0402"
BOM_COST"PROC_SOCKET"
WATTAGE"1/16W"
MATERIAL"CHIP"
PACK_TYPE"0402"
TOLERANCE"1.0%"
VALUE"2"
PART_NUMBER"G21796-274"
LOCATION"R9L3";
"B"
$PN"2"22;
"A"
$PN"1"21;
%"CAP_A"
"1","(2450,1650)","0","dev_discrete","I46";
;
ROOM"MEM"
SEC"1"
SEC_TYPE"0402V"
CDS_SEC"1"
CDS_LIB"dev_discrete"
BOM_COST"SM_CONTROLLER"
CDS_LOCATION"C9L3"
MATERIAL"X7R"
VOLTAGE"25V"
PACK_TYPE"0402V"
TOLERANCE"10%"
VALUE"0.01UF"
PART_NUMBER"A36096-045"
LOCATION"C9L3";
"B"
$PN"2"10;
"A"
$PN"1"21;
%"GND"
"1","(2675,1300)","0","mstr_symbols","I47";
;
HDL_POWER"GND"
BODY_TYPE"PLUMBING"
SIZE"1B"
CDS_LIB"mstr_symbols"
VOLTAGE"0";
"A\NAC"10;
%"PVDDQ_GHJ"
"1","(-1900,4200)","0","mstr_symbols","I5";
;
HDL_POWER"PVDDQ_GHJ"
BODY_TYPE"PLUMBING"
CDS_LIB"mstr_symbols"
VOLTAGE"1.2V";
"G\NAC"11;
%"RES"
"2","(-1900,3950)","2","mstr_discrete","I6";
;
CDS_SEC"1"
ROOM"MEM"
CDS_LOCATION"R1F5"
SEC"1"
SEC_TYPE"0402"
BOM_COST"SM_CONTROLLER"
CDS_LIB"mstr_discrete"
WATTAGE"1/16W"
MATERIAL"CHIP"
PACK_TYPE"0402"
TOLERANCE"1%"
VALUE"1.00K"
PART_NUMBER"G21796-026"
LOCATION"R1F5";
"A"
$PN"1"11;
"B"
$PN"2"16;
%"RES"
"1","(-2125,3625)","0","mstr_discrete","I7";
;
CDS_SEC"1"
ROOM"PROC"
CDS_LOCATION"R1F4"
SEC"1"
SEC_TYPE"0402"
CDS_LIB"mstr_discrete"
BOM_COST"PROC_SOCKET"
WATTAGE"1/16W"
MATERIAL"CHIP"
PACK_TYPE"0402"
TOLERANCE"1.0%"
VALUE"2"
PART_NUMBER"G21796-274"
LOCATION"R1F4";
"B"
$PN"2"16;
"A"
$PN"1"14;
%"CAP_A"
"1","(-2350,3325)","0","dev_discrete","I8";
;
ROOM"PROC"
SEC"1"
SEC_TYPE"0402V"
CDS_SEC"1"
CDS_LIB"dev_discrete"
BOM_COST"PROC_SOCKET"
CDS_LOCATION"C1F19"
MATERIAL"X7R"
VOLTAGE"25V"
PACK_TYPE"0402V"
TOLERANCE"10%"
VALUE"0.01UF"
PART_NUMBER"A36096-045"
LOCATION"C1F19";
"B"
$PN"2"12;
"A"
$PN"1"14;
%"GND"
"1","(-2125,2975)","0","mstr_symbols","I9";
;
HDL_POWER"GND"
BODY_TYPE"PLUMBING"
CDS_LIB"mstr_symbols"
SIZE"1B"
VOLTAGE"0";
"A\NAC"12;
END.
